# T6G (Grand Teton) — schematic netlist excerpt (pin names and nets, part order shuffled) for the footprints in the layout excerpt that follows; sources: Cadence DE-HDL packaged netlist, KiCad conversion of 04192023_DAF0TMB3IC0_F0TG_MB_C_brd_V02_OCP.brd

R48  Q_RES  200 1% CHIP  pkg 0402LF  page 131 : A = SMB_OCP_SFF_3V3AUX_BUF_R_SDA ; B = SMB_OCP_SFF_3V3AUX_BUF_SDA
R610  Q_RES  1K 1% EMPTY  pkg 0402LF  page 77 : A = P3V3_AUX ; B = SPI_CPU0_LVC3_SCM_CS0_N
H11  HOLE  EMPTY  pkg TH  page 230 : \1\ = GND

(kicad_pcb
	(version 20260206)
	(generator "pcbnew")
	(generator_version "10.0")
	(general
		(thickness 1.6)
		(legacy_teardrops no)
	)
	(paper "A4")
	(title_block
		(title "04192023_DAF0TMB3IC0_F0TG_MB_C_brd_V02_OCP.brd")
		(comment 1 "Grand Teton / footprints 3047-3049 of 8354")
	)
	(layers
		(0 "F.Cu" signal "TOP")
		(4 "In1.Cu" signal "GND")
		(6 "In2.Cu" signal "IN1")
		(8 "In3.Cu" signal "GND1")
		(10 "In4.Cu" signal "IN2")
		(12 "In5.Cu" signal "GND2")
		(14 "In6.Cu" signal "IN3")
		(16 "In7.Cu" signal "GND3")
		(18 "In8.Cu" signal "VCC")
		(20 "In9.Cu" signal "VCC1")
		(22 "In10.Cu" signal "GND4")
		(24 "In11.Cu" signal "IN4")
		(26 "In12.Cu" signal "GND5")
		(28 "In13.Cu" signal "IN5")
		(30 "In14.Cu" signal "GND6")
		(32 "In15.Cu" signal "IN6")
		(34 "In16.Cu" signal "GND7")
		(2 "B.Cu" signal "BOTTOM")
		(9 "F.Adhes" user "F.Adhesive")
		(11 "B.Adhes" user "B.Adhesive")
		(13 "F.Paste" user "Package Geometry/Pastemask Top")
		(15 "B.Paste" user "Package Geometry/Pastemask Bottom")
		(5 "F.SilkS" user "Ref Des/Silkscreen Top")
		(7 "B.SilkS" user "Ref Des/Silkscreen Bottom")
		(1 "F.Mask" user "Board Geometry/Soldermask Top")
		(3 "B.Mask" user "Board Geometry/Soldermask Bottom")
		(17 "Dwgs.User" user "User.Drawings")
		(19 "Cmts.User" user "User.Comments")
		(21 "Eco1.User" user "User.Eco1")
		(23 "Eco2.User" user "User.Eco2")
		(25 "Edge.Cuts" user "Board Geometry/Outline")
		(27 "Margin" user)
		(31 "F.CrtYd" user "Package Geometry/Place Bound Top")
		(29 "B.CrtYd" user "Package Geometry/Place Bound Bottom")
		(35 "F.Fab" user "Ref Des/Assembly Top")
		(33 "B.Fab" user "Ref Des/Assembly Bottom")
	)
	(footprint ""
		(layer "F.Cu")
		(at 251.474224 -131.067556)
		(property "Reference" "R610"
			(at 0 0 0)
			(layer "F.SilkS")
			(hide yes)
			(effects
				(font
					(size 1.27 1.27)
				)
			)
		)
		(property "Value" ""
			(at 0 0 0)
			(layer "F.Fab")
			(effects
				(font
					(size 1.27 1.27)
				)
			)
		)
		(duplicate_pad_numbers_are_jumpers no)
		(fp_line
			(start -0.7874 -0.4064)
			(end 0.7874 -0.4064)
			(stroke
				(width 0.1524)
				(type default)
			)
			(layer "F.SilkS")
		)
		(fp_line
			(start -0.7874 0.4064)
			(end -0.7874 -0.4064)
			(stroke
				(width 0.1524)
				(type default)
			)
			(layer "F.SilkS")
		)
		(fp_line
			(start 0.7874 -0.4064)
			(end 0.7874 0.4064)
			(stroke
				(width 0.1524)
				(type default)
			)
			(layer "F.SilkS")
		)
		(fp_line
			(start 0.7874 0.4064)
			(end -0.7874 0.4064)
			(stroke
				(width 0.1524)
				(type default)
			)
			(layer "F.SilkS")
		)
		(fp_line
			(start -0.67945 -0.305054)
			(end -0.12065 -0.305054)
			(stroke
				(width 0.1)
				(type default)
			)
			(layer "F.Fab")
		)
		(fp_line
			(start -0.67945 0.3048)
			(end -0.67945 -0.305054)
			(stroke
				(width 0.1)
				(type default)
			)
			(layer "F.Fab")
		)
		(fp_line
			(start -0.12065 -0.305054)
			(end -0.12065 -0.2794)
			(stroke
				(width 0.1)
				(type default)
			)
			(layer "F.Fab")
		)
		(fp_line
			(start -0.12065 -0.2794)
			(end 0.12065 -0.2794)
			(stroke
				(width 0.1)
				(type default)
			)
			(layer "F.Fab")
		)
		(fp_line
			(start -0.12065 0.2794)
			(end -0.12065 0.3048)
			(stroke
				(width 0.1)
				(type default)
			)
			(layer "F.Fab")
		)
		(fp_line
			(start -0.12065 0.3048)
			(end -0.67945 0.3048)
			(stroke
				(width 0.1)
				(type default)
			)
			(layer "F.Fab")
		)
		(fp_line
			(start 0.120396 0.2794)
			(end -0.12065 0.2794)
			(stroke
				(width 0.1)
				(type default)
			)
			(layer "F.Fab")
		)
		(fp_line
			(start 0.120396 0.3048)
			(end 0.120396 0.2794)
			(stroke
				(width 0.1)
				(type default)
			)
			(layer "F.Fab")
		)
		(fp_line
			(start 0.12065 -0.3048)
			(end 0.67945 -0.3048)
			(stroke
				(width 0.1)
				(type default)
			)
			(layer "F.Fab")
		)
		(fp_line
			(start 0.12065 -0.2794)
			(end 0.12065 -0.3048)
			(stroke
				(width 0.1)
				(type default)
			)
			(layer "F.Fab")
		)
		(fp_line
			(start 0.67945 -0.3048)
			(end 0.67945 0.3048)
			(stroke
				(width 0.1)
				(type default)
			)
			(layer "F.Fab")
		)
		(fp_line
			(start 0.67945 0.3048)
			(end 0.120396 0.3048)
			(stroke
				(width 0.1)
				(type default)
			)
			(layer "F.Fab")
		)
		(pad "1" smd circle
			(at -0.40005 0)
			(size 0 0)
			(layers "F.Cu" "F.Mask" "F.Paste")
			(net "P3V3_AUX")
		)
		(pad "2" smd circle
			(at 0.40005 0)
			(size 0 0)
			(layers "F.Cu" "F.Mask" "F.Paste")
			(net "SPI_CPU0_LVC3_SCM_CS0_N")
		)
	)
	(footprint ""
		(layer "F.Cu")
		(at 412.472886 -73.848468 180)
		(property "Reference" "R48"
			(at 0 0 180)
			(layer "F.SilkS")
			(hide yes)
			(effects
				(font
					(size 1.27 1.27)
				)
			)
		)
		(property "Value" ""
			(at 0 0 180)
			(layer "F.Fab")
			(effects
				(font
					(size 1.27 1.27)
				)
			)
		)
		(duplicate_pad_numbers_are_jumpers no)
		(fp_line
			(start 0.7874 0.4064)
			(end -0.7874 0.4064)
			(stroke
				(width 0.1524)
				(type default)
			)
			(layer "F.SilkS")
		)
		(fp_line
			(start 0.7874 -0.4064)
			(end 0.7874 0.4064)
			(stroke
				(width 0.1524)
				(type default)
			)
			(layer "F.SilkS")
		)
		(fp_line
			(start -0.7874 0.4064)
			(end -0.7874 -0.4064)
			(stroke
				(width 0.1524)
				(type default)
			)
			(layer "F.SilkS")
		)
		(fp_line
			(start -0.7874 -0.4064)
			(end 0.7874 -0.4064)
			(stroke
				(width 0.1524)
				(type default)
			)
			(layer "F.SilkS")
		)
		(fp_line
			(start 0.67945 0.3048)
			(end 0.120396 0.3048)
			(stroke
				(width 0.1)
				(type default)
			)
			(layer "F.Fab")
		)
		(fp_line
			(start 0.67945 -0.3048)
			(end 0.67945 0.3048)
			(stroke
				(width 0.1)
				(type default)
			)
			(layer "F.Fab")
		)
		(fp_line
			(start 0.12065 -0.2794)
			(end 0.12065 -0.3048)
			(stroke
				(width 0.1)
				(type default)
			)
			(layer "F.Fab")
		)
		(fp_line
			(start 0.12065 -0.3048)
			(end 0.67945 -0.3048)
			(stroke
				(width 0.1)
				(type default)
			)
			(layer "F.Fab")
		)
		(fp_line
			(start 0.120396 0.3048)
			(end 0.120396 0.2794)
			(stroke
				(width 0.1)
				(type default)
			)
			(layer "F.Fab")
		)
		(fp_line
			(start 0.120396 0.2794)
			(end -0.12065 0.2794)
			(stroke
				(width 0.1)
				(type default)
			)
			(layer "F.Fab")
		)
		(fp_line
			(start -0.12065 0.3048)
			(end -0.67945 0.3048)
			(stroke
				(width 0.1)
				(type default)
			)
			(layer "F.Fab")
		)
		(fp_line
			(start -0.12065 0.2794)
			(end -0.12065 0.3048)
			(stroke
				(width 0.1)
				(type default)
			)
			(layer "F.Fab")
		)
		(fp_line
			(start -0.12065 -0.2794)
			(end 0.12065 -0.2794)
			(stroke
				(width 0.1)
				(type default)
			)
			(layer "F.Fab")
		)
		(fp_line
			(start -0.12065 -0.305054)
			(end -0.12065 -0.2794)
			(stroke
				(width 0.1)
				(type default)
			)
			(layer "F.Fab")
		)
		(fp_line
			(start -0.67945 0.3048)
			(end -0.67945 -0.305054)
			(stroke
				(width 0.1)
				(type default)
			)
			(layer "F.Fab")
		)
		(fp_line
			(start -0.67945 -0.305054)
			(end -0.12065 -0.305054)
			(stroke
				(width 0.1)
				(type default)
			)
			(layer "F.Fab")
		)
		(pad "1" smd circle
			(at -0.40005 0 180)
			(size 0 0)
			(layers "F.Cu" "F.Mask" "F.Paste")
			(net "SMB_OCP_SFF_3V3AUX_BUF_R_SDA")
		)
		(pad "2" smd circle
			(at 0.40005 0 180)
			(size 0 0)
			(layers "F.Cu" "F.Mask" "F.Paste")
			(net "SMB_OCP_SFF_3V3AUX_BUF_SDA")
		)
	)
	(footprint ""
		(layer "F.Cu")
		(at 20.21586 -347.8149)
		(property "Reference" "H11"
			(at 0.9144 3.91287 0)
			(unlocked yes)
			(layer "F.SilkS")
			(effects
				(font
					(size 0.7874 0.5842)
					(thickness 0.1524)
				)
				(justify left)
			)
		)
		(property "Value" ""
			(at 0 0 0)
			(layer "F.Fab")
			(effects
				(font
					(size 1.27 1.27)
				)
			)
		)
		(duplicate_pad_numbers_are_jumpers no)
		(pad "1" thru_hole circle
			(at 0 0)
			(size 6.1976 6.1976)
			(drill 3.7338)
			(layers "*.Cu" "*.Mask")
			(remove_unused_layers no)
			(net "GND")
			(clearance -0.9779)
			(padstack
				(mode front_inner_back)
				(layer "Inner"
					(shape circle)
					(size 5.5372 5.5372)
					(clearance -0.6477)
				)
				(layer "B.Cu"
					(shape circle)
					(size 6.1976 6.1976)
					(clearance -0.9779)
				)
			)
		)
	)
)
